(kicad_pcb
	(version 20260206)
	(generator "pcbnew")
	(generator_version "10.0")
	(general
		(thickness 1.6)
		(legacy_teardrops no)
	)
	(paper "A4")
	(title_block
		(title "Wiwynn_Tioga_Pass_MB.brd")
		(comment 1 "Tioga Pass / footprint 990 of 4770 (J4B1), pads 244-291 of 291")
	)
	(layers
		(0 "F.Cu" signal "TOP")
		(4 "In1.Cu" signal "L2GND")
		(6 "In2.Cu" signal "L3")
		(8 "In3.Cu" signal "L4GND")
		(10 "In4.Cu" signal "L5")
		(12 "In5.Cu" signal "L6GND")
		(14 "In6.Cu" signal "L7VCC")
		(16 "In7.Cu" signal "L8VCC")
		(18 "In8.Cu" signal "L9GND")
		(20 "In9.Cu" signal "L10")
		(22 "In10.Cu" signal "L11GND")
		(24 "In11.Cu" signal "L12")
		(26 "In12.Cu" signal "L13GND")
		(2 "B.Cu" signal "BOTTOM")
		(9 "F.Adhes" user "F.Adhesive")
		(11 "B.Adhes" user "B.Adhesive")
		(13 "F.Paste" user "Package Geometry/Pastemask Top")
		(15 "B.Paste" user "Package Geometry/Pastemask Bottom")
		(5 "F.SilkS" user "Ref Des/Silkscreen Top")
		(7 "B.SilkS" user "Ref Des/Silkscreen Bottom")
		(1 "F.Mask" user "Board Geometry/Soldermask Top")
		(3 "B.Mask" user "Board Geometry/Soldermask Bottom")
		(17 "Dwgs.User" user "User.Drawings")
		(19 "Cmts.User" user "User.Comments")
		(21 "Eco1.User" user "User.Eco1")
		(23 "Eco2.User" user "User.Eco2")
		(25 "Edge.Cuts" user "Board Geometry/Outline")
		(27 "Margin" user)
		(31 "F.CrtYd" user "Package Geometry/Place Bound Top")
		(29 "B.CrtYd" user "Package Geometry/Place Bound Bottom")
		(35 "F.Fab" user "Ref Des/Assembly Top")
		(33 "B.Fab" user "Ref Des/Assembly Bottom")
	)
	(footprint ""
		(layer "F.Cu")
		(at 194.700398 -133.0706 90)
		(property "Reference" "J4B1"
			(at -5.087112 42.28211 0)
			(unlocked yes)
			(layer "F.SilkS")
			(effects
				(font
					(size 0.7874 0.5842)
					(thickness 0.1524)
				)
				(justify left)
			)
		)
		(property "Value" ""
			(at 0 0 90)
			(layer "F.Fab")
			(effects
				(font
					(size 1.27 1.27)
				)
			)
		)
		(duplicate_pad_numbers_are_jumpers no)
		(pad "241" smd rect
			(at 4.59994 86.700106 90)
			(size 1.8034 0.508)
			(layers "F.Cu" "F.Mask" "F.Paste")
			(net "GND")
		)
		(pad "242" smd rect
			(at 4.59994 87.54999 90)
			(size 1.8034 0.508)
			(layers "F.Cu" "F.Mask" "F.Paste")
			(net "M_D_DQ<32>")
		)
		(pad "243" smd rect
			(at 4.59994 88.399874 90)
			(size 1.8034 0.508)
			(layers "F.Cu" "F.Mask" "F.Paste")
			(net "GND")
		)
		(pad "244" smd rect
			(at 4.59994 89.250012 90)
			(size 1.8034 0.508)
			(layers "F.Cu" "F.Mask" "F.Paste")
			(net "M_D_DQS_DN<4>")
		)
		(pad "245" smd rect
			(at 4.59994 90.099896 90)
			(size 1.8034 0.508)
			(layers "F.Cu" "F.Mask" "F.Paste")
			(net "M_D_DQS_DP<4>")
		)
		(pad "246" smd rect
			(at 4.59994 90.950034 90)
			(size 1.8034 0.508)
			(layers "F.Cu" "F.Mask" "F.Paste")
			(net "GND")
		)
		(pad "247" smd rect
			(at 4.59994 91.799918 90)
			(size 1.8034 0.508)
			(layers "F.Cu" "F.Mask" "F.Paste")
			(net "M_D_DQ<38>")
		)
		(pad "248" smd rect
			(at 4.59994 92.650056 90)
			(size 1.8034 0.508)
			(layers "F.Cu" "F.Mask" "F.Paste")
			(net "GND")
		)
		(pad "249" smd rect
			(at 4.59994 93.49994 90)
			(size 1.8034 0.508)
			(layers "F.Cu" "F.Mask" "F.Paste")
			(net "M_D_DQ<34>")
		)
		(pad "250" smd rect
			(at 4.59994 94.350078 90)
			(size 1.8034 0.508)
			(layers "F.Cu" "F.Mask" "F.Paste")
			(net "GND")
		)
		(pad "251" smd rect
			(at 4.59994 95.199962 90)
			(size 1.8034 0.508)
			(layers "F.Cu" "F.Mask" "F.Paste")
			(net "M_D_DQ<44>")
		)
		(pad "252" smd rect
			(at 4.59994 96.0501 90)
			(size 1.8034 0.508)
			(layers "F.Cu" "F.Mask" "F.Paste")
			(net "GND")
		)
		(pad "253" smd rect
			(at 4.59994 96.899984 90)
			(size 1.8034 0.508)
			(layers "F.Cu" "F.Mask" "F.Paste")
			(net "M_D_DQ<40>")
		)
		(pad "254" smd rect
			(at 4.59994 97.750122 90)
			(size 1.8034 0.508)
			(layers "F.Cu" "F.Mask" "F.Paste")
			(net "GND")
		)
		(pad "255" smd rect
			(at 4.59994 98.600006 90)
			(size 1.8034 0.508)
			(layers "F.Cu" "F.Mask" "F.Paste")
			(net "M_D_DQS_DN<5>")
		)
		(pad "256" smd rect
			(at 4.59994 99.44989 90)
			(size 1.8034 0.508)
			(layers "F.Cu" "F.Mask" "F.Paste")
			(net "M_D_DQS_DP<5>")
		)
		(pad "257" smd rect
			(at 4.59994 100.300028 90)
			(size 1.8034 0.508)
			(layers "F.Cu" "F.Mask" "F.Paste")
			(net "GND")
		)
		(pad "258" smd rect
			(at 4.59994 101.149912 90)
			(size 1.8034 0.508)
			(layers "F.Cu" "F.Mask" "F.Paste")
			(net "M_D_DQ<46>")
		)
		(pad "259" smd rect
			(at 4.59994 102.00005 90)
			(size 1.8034 0.508)
			(layers "F.Cu" "F.Mask" "F.Paste")
			(net "GND")
		)
		(pad "260" smd rect
			(at 4.59994 102.849934 90)
			(size 1.8034 0.508)
			(layers "F.Cu" "F.Mask" "F.Paste")
			(net "M_D_DQ<42>")
		)
		(pad "261" smd rect
			(at 4.59994 103.700072 90)
			(size 1.8034 0.508)
			(layers "F.Cu" "F.Mask" "F.Paste")
			(net "GND")
		)
		(pad "262" smd rect
			(at 4.59994 104.549956 90)
			(size 1.8034 0.508)
			(layers "F.Cu" "F.Mask" "F.Paste")
			(net "M_D_DQ<52>")
		)
		(pad "263" smd rect
			(at 4.59994 105.400094 90)
			(size 1.8034 0.508)
			(layers "F.Cu" "F.Mask" "F.Paste")
			(net "GND")
		)
		(pad "264" smd rect
			(at 4.59994 106.249978 90)
			(size 1.8034 0.508)
			(layers "F.Cu" "F.Mask" "F.Paste")
			(net "M_D_DQ<48>")
		)
		(pad "265" smd rect
			(at 4.59994 107.100116 90)
			(size 1.8034 0.508)
			(layers "F.Cu" "F.Mask" "F.Paste")
			(net "GND")
		)
		(pad "266" smd rect
			(at 4.59994 107.95 90)
			(size 1.8034 0.508)
			(layers "F.Cu" "F.Mask" "F.Paste")
			(net "M_D_DQS_DN<6>")
		)
		(pad "267" smd rect
			(at 4.59994 108.799884 90)
			(size 1.8034 0.508)
			(layers "F.Cu" "F.Mask" "F.Paste")
			(net "M_D_DQS_DP<6>")
		)
		(pad "268" smd rect
			(at 4.59994 109.650022 90)
			(size 1.8034 0.508)
			(layers "F.Cu" "F.Mask" "F.Paste")
			(net "GND")
		)
		(pad "269" smd rect
			(at 4.59994 110.499906 90)
			(size 1.8034 0.508)
			(layers "F.Cu" "F.Mask" "F.Paste")
			(net "M_D_DQ<54>")
		)
		(pad "270" smd rect
			(at 4.59994 111.350044 90)
			(size 1.8034 0.508)
			(layers "F.Cu" "F.Mask" "F.Paste")
			(net "GND")
		)
		(pad "271" smd rect
			(at 4.59994 112.199928 90)
			(size 1.8034 0.508)
			(layers "F.Cu" "F.Mask" "F.Paste")
			(net "M_D_DQ<50>")
		)
		(pad "272" smd rect
			(at 4.59994 113.050066 90)
			(size 1.8034 0.508)
			(layers "F.Cu" "F.Mask" "F.Paste")
			(net "GND")
		)
		(pad "273" smd rect
			(at 4.59994 113.89995 90)
			(size 1.8034 0.508)
			(layers "F.Cu" "F.Mask" "F.Paste")
			(net "M_D_DQ<60>")
		)
		(pad "274" smd rect
			(at 4.59994 114.750088 90)
			(size 1.8034 0.508)
			(layers "F.Cu" "F.Mask" "F.Paste")
			(net "GND")
		)
		(pad "275" smd rect
			(at 4.59994 115.599972 90)
			(size 1.8034 0.508)
			(layers "F.Cu" "F.Mask" "F.Paste")
			(net "M_D_DQ<56>")
		)
		(pad "276" smd rect
			(at 4.59994 116.45011 90)
			(size 1.8034 0.508)
			(layers "F.Cu" "F.Mask" "F.Paste")
			(net "GND")
		)
		(pad "277" smd rect
			(at 4.59994 117.299994 90)
			(size 1.8034 0.508)
			(layers "F.Cu" "F.Mask" "F.Paste")
			(net "M_D_DQS_DN<7>")
		)
		(pad "278" smd rect
			(at 4.59994 118.149878 90)
			(size 1.8034 0.508)
			(layers "F.Cu" "F.Mask" "F.Paste")
			(net "M_D_DQS_DP<7>")
		)
		(pad "279" smd rect
			(at 4.59994 119.000016 90)
			(size 1.8034 0.508)
			(layers "F.Cu" "F.Mask" "F.Paste")
			(net "GND")
		)
		(pad "280" smd rect
			(at 4.59994 119.8499 90)
			(size 1.8034 0.508)
			(layers "F.Cu" "F.Mask" "F.Paste")
			(net "M_D_DQ<62>")
		)
		(pad "281" smd rect
			(at 4.59994 120.700038 90)
			(size 1.8034 0.508)
			(layers "F.Cu" "F.Mask" "F.Paste")
			(net "GND")
		)
		(pad "282" smd rect
			(at 4.59994 121.549922 90)
			(size 1.8034 0.508)
			(layers "F.Cu" "F.Mask" "F.Paste")
			(net "M_D_DQ<58>")
		)
		(pad "283" smd rect
			(at 4.59994 122.40006 90)
			(size 1.8034 0.508)
			(layers "F.Cu" "F.Mask" "F.Paste")
			(net "GND")
		)
		(pad "284" smd rect
			(at 4.59994 123.249944 90)
			(size 1.8034 0.508)
			(layers "F.Cu" "F.Mask" "F.Paste")
			(net "PVPP_DEF")
		)
		(pad "285" smd rect
			(at 4.59994 124.100082 90)
			(size 1.8034 0.508)
			(layers "F.Cu" "F.Mask" "F.Paste")
			(net "SMB_DDR_DEF_VPP_SDA")
		)
		(pad "286" smd rect
			(at 4.59994 124.949966 90)
			(size 1.8034 0.508)
			(layers "F.Cu" "F.Mask" "F.Paste")
			(net "PVPP_DEF")
		)
		(pad "287" smd rect
			(at 4.59994 125.800104 90)
			(size 1.8034 0.508)
			(layers "F.Cu" "F.Mask" "F.Paste")
			(net "PVPP_DEF")
		)
		(pad "288" smd rect
			(at 4.59994 126.649988 90)
			(size 1.8034 0.508)
			(layers "F.Cu" "F.Mask" "F.Paste")
			(net "PVPP_DEF")
		)
	)
)
